# T6G (Grand Teton) — schematic netlist excerpt (pin names and nets, part order shuffled) for the footprints in the layout excerpt that follows; sources: Cadence DE-HDL packaged netlist, KiCad conversion of 04192023_DAF0TMB3IC0_F0TG_MB_C_brd_V02_OCP.brd

C354  Q_CAP  10UF 6.3V 20% X6S  pkg C0402  page 334 : A = P0V9_CPU1_RT1_2A ; B = GND
R410  Q_RES  2.2K 5% CHIP  pkg 0402LF  page 27 : A = CPU0_BP2 ; B = PVDD18_S5_P0

(kicad_pcb
	(version 20260206)
	(generator "pcbnew")
	(generator_version "10.0")
	(general
		(thickness 1.6)
		(legacy_teardrops no)
	)
	(paper "A4")
	(title_block
		(title "04192023_DAF0TMB3IC0_F0TG_MB_C_brd_V02_OCP.brd")
		(comment 1 "Grand Teton / footprints 6220-6221 of 8354")
	)
	(layers
		(0 "F.Cu" signal "TOP")
		(4 "In1.Cu" signal "GND")
		(6 "In2.Cu" signal "IN1")
		(8 "In3.Cu" signal "GND1")
		(10 "In4.Cu" signal "IN2")
		(12 "In5.Cu" signal "GND2")
		(14 "In6.Cu" signal "IN3")
		(16 "In7.Cu" signal "GND3")
		(18 "In8.Cu" signal "VCC")
		(20 "In9.Cu" signal "VCC1")
		(22 "In10.Cu" signal "GND4")
		(24 "In11.Cu" signal "IN4")
		(26 "In12.Cu" signal "GND5")
		(28 "In13.Cu" signal "IN5")
		(30 "In14.Cu" signal "GND6")
		(32 "In15.Cu" signal "IN6")
		(34 "In16.Cu" signal "GND7")
		(2 "B.Cu" signal "BOTTOM")
		(9 "F.Adhes" user "F.Adhesive")
		(11 "B.Adhes" user "B.Adhesive")
		(13 "F.Paste" user "Package Geometry/Pastemask Top")
		(15 "B.Paste" user "Package Geometry/Pastemask Bottom")
		(5 "F.SilkS" user "Ref Des/Silkscreen Top")
		(7 "B.SilkS" user "Ref Des/Silkscreen Bottom")
		(1 "F.Mask" user "Board Geometry/Soldermask Top")
		(3 "B.Mask" user "Board Geometry/Soldermask Bottom")
		(17 "Dwgs.User" user "User.Drawings")
		(19 "Cmts.User" user "User.Comments")
		(21 "Eco1.User" user "User.Eco1")
		(23 "Eco2.User" user "User.Eco2")
		(25 "Edge.Cuts" user "Board Geometry/Outline")
		(27 "Margin" user)
		(31 "F.CrtYd" user "Package Geometry/Place Bound Top")
		(29 "B.CrtYd" user "Package Geometry/Place Bound Bottom")
		(35 "F.Fab" user "Ref Des/Assembly Top")
		(33 "B.Fab" user "Ref Des/Assembly Bottom")
	)
	(footprint ""
		(layer "B.Cu")
		(at 97.919032 -390.560052 90)
		(property "Reference" "C354"
			(at 0 0 90)
			(layer "B.SilkS")
			(hide yes)
			(effects
				(font
					(size 1.27 1.27)
				)
				(justify mirror)
			)
		)
		(property "Value" ""
			(at 0 0 90)
			(layer "B.Fab")
			(effects
				(font
					(size 1.27 1.27)
				)
				(justify mirror)
			)
		)
		(duplicate_pad_numbers_are_jumpers no)
		(fp_line
			(start 0.7874 -0.4064)
			(end -0.7874 -0.4064)
			(stroke
				(width 0.1524)
				(type default)
			)
			(layer "B.SilkS")
		)
		(fp_line
			(start -0.7874 -0.4064)
			(end -0.7874 0.4064)
			(stroke
				(width 0.1524)
				(type default)
			)
			(layer "B.SilkS")
		)
		(fp_line
			(start 0.7874 0.4064)
			(end 0.7874 -0.4064)
			(stroke
				(width 0.1524)
				(type default)
			)
			(layer "B.SilkS")
		)
		(fp_line
			(start -0.7874 0.4064)
			(end 0.7874 0.4064)
			(stroke
				(width 0.1524)
				(type default)
			)
			(layer "B.SilkS")
		)
		(fp_line
			(start 0.67945 -0.305054)
			(end 0.12065 -0.305054)
			(stroke
				(width 0.1)
				(type default)
			)
			(layer "B.Fab")
		)
		(fp_line
			(start 0.12065 -0.305054)
			(end 0.12065 -0.2794)
			(stroke
				(width 0.1)
				(type default)
			)
			(layer "B.Fab")
		)
		(fp_line
			(start -0.12065 -0.3048)
			(end -0.67945 -0.3048)
			(stroke
				(width 0.1)
				(type default)
			)
			(layer "B.Fab")
		)
		(fp_line
			(start -0.67945 -0.3048)
			(end -0.67945 0.3048)
			(stroke
				(width 0.1)
				(type default)
			)
			(layer "B.Fab")
		)
		(fp_line
			(start 0.12065 -0.2794)
			(end -0.12065 -0.2794)
			(stroke
				(width 0.1)
				(type default)
			)
			(layer "B.Fab")
		)
		(fp_line
			(start -0.12065 -0.2794)
			(end -0.12065 -0.3048)
			(stroke
				(width 0.1)
				(type default)
			)
			(layer "B.Fab")
		)
		(fp_line
			(start 0.12065 0.2794)
			(end 0.12065 0.3048)
			(stroke
				(width 0.1)
				(type default)
			)
			(layer "B.Fab")
		)
		(fp_line
			(start -0.120396 0.2794)
			(end 0.12065 0.2794)
			(stroke
				(width 0.1)
				(type default)
			)
			(layer "B.Fab")
		)
		(fp_line
			(start 0.67945 0.3048)
			(end 0.67945 -0.305054)
			(stroke
				(width 0.1)
				(type default)
			)
			(layer "B.Fab")
		)
		(fp_line
			(start 0.12065 0.3048)
			(end 0.67945 0.3048)
			(stroke
				(width 0.1)
				(type default)
			)
			(layer "B.Fab")
		)
		(fp_line
			(start -0.120396 0.3048)
			(end -0.120396 0.2794)
			(stroke
				(width 0.1)
				(type default)
			)
			(layer "B.Fab")
		)
		(fp_line
			(start -0.67945 0.3048)
			(end -0.120396 0.3048)
			(stroke
				(width 0.1)
				(type default)
			)
			(layer "B.Fab")
		)
		(pad "1" smd circle
			(at 0.40005 0 270)
			(size 0 0)
			(layers "B.Cu" "B.Mask" "B.Paste")
			(net "P0V9_CPU1_RT1_2A")
		)
		(pad "2" smd circle
			(at -0.40005 0 270)
			(size 0 0)
			(layers "B.Cu" "B.Mask" "B.Paste")
			(net "GND")
		)
	)
	(footprint ""
		(layer "B.Cu")
		(at 322.878958 -196.678296)
		(property "Reference" "R410"
			(at 0 0 0)
			(layer "B.SilkS")
			(hide yes)
			(effects
				(font
					(size 1.27 1.27)
				)
				(justify mirror)
			)
		)
		(property "Value" ""
			(at 0 0 0)
			(layer "B.Fab")
			(effects
				(font
					(size 1.27 1.27)
				)
				(justify mirror)
			)
		)
		(duplicate_pad_numbers_are_jumpers no)
		(fp_line
			(start -0.7874 -0.4064)
			(end -0.7874 0.4064)
			(stroke
				(width 0.1524)
				(type default)
			)
			(layer "B.SilkS")
		)
		(fp_line
			(start -0.7874 0.4064)
			(end 0.7874 0.4064)
			(stroke
				(width 0.1524)
				(type default)
			)
			(layer "B.SilkS")
		)
		(fp_line
			(start 0.7874 -0.4064)
			(end -0.7874 -0.4064)
			(stroke
				(width 0.1524)
				(type default)
			)
			(layer "B.SilkS")
		)
		(fp_line
			(start 0.7874 0.4064)
			(end 0.7874 -0.4064)
			(stroke
				(width 0.1524)
				(type default)
			)
			(layer "B.SilkS")
		)
		(fp_line
			(start -0.67945 -0.3048)
			(end -0.67945 0.3048)
			(stroke
				(width 0.1)
				(type default)
			)
			(layer "B.Fab")
		)
		(fp_line
			(start -0.67945 0.3048)
			(end -0.120396 0.3048)
			(stroke
				(width 0.1)
				(type default)
			)
			(layer "B.Fab")
		)
		(fp_line
			(start -0.12065 -0.3048)
			(end -0.67945 -0.3048)
			(stroke
				(width 0.1)
				(type default)
			)
			(layer "B.Fab")
		)
		(fp_line
			(start -0.12065 -0.2794)
			(end -0.12065 -0.3048)
			(stroke
				(width 0.1)
				(type default)
			)
			(layer "B.Fab")
		)
		(fp_line
			(start -0.120396 0.2794)
			(end 0.12065 0.2794)
			(stroke
				(width 0.1)
				(type default)
			)
			(layer "B.Fab")
		)
		(fp_line
			(start -0.120396 0.3048)
			(end -0.120396 0.2794)
			(stroke
				(width 0.1)
				(type default)
			)
			(layer "B.Fab")
		)
		(fp_line
			(start 0.12065 -0.305054)
			(end 0.12065 -0.2794)
			(stroke
				(width 0.1)
				(type default)
			)
			(layer "B.Fab")
		)
		(fp_line
			(start 0.12065 -0.2794)
			(end -0.12065 -0.2794)
			(stroke
				(width 0.1)
				(type default)
			)
			(layer "B.Fab")
		)
		(fp_line
			(start 0.12065 0.2794)
			(end 0.12065 0.3048)
			(stroke
				(width 0.1)
				(type default)
			)
			(layer "B.Fab")
		)
		(fp_line
			(start 0.12065 0.3048)
			(end 0.67945 0.3048)
			(stroke
				(width 0.1)
				(type default)
			)
			(layer "B.Fab")
		)
		(fp_line
			(start 0.67945 -0.305054)
			(end 0.12065 -0.305054)
			(stroke
				(width 0.1)
				(type default)
			)
			(layer "B.Fab")
		)
		(fp_line
			(start 0.67945 0.3048)
			(end 0.67945 -0.305054)
			(stroke
				(width 0.1)
				(type default)
			)
			(layer "B.Fab")
		)
		(pad "1" smd circle
			(at 0.40005 0 180)
			(size 0 0)
			(layers "B.Cu" "B.Mask" "B.Paste")
			(net "CPU0_BP2")
		)
		(pad "2" smd circle
			(at -0.40005 0 180)
			(size 0 0)
			(layers "B.Cu" "B.Mask" "B.Paste")
			(net "PVDD18_S5_P0")
		)
	)
)
